(kicad_pcb
	(version 20260206)
	(generator "pcbnew")
	(generator_version "10.0")
	(general
		(thickness 1.6)
		(legacy_teardrops no)
	)
	(paper "A4")
	(title_block
		(title "01162023_DA0F0TEBIF0_F0T_Expander_BD_F_brd_V02_OCP.brd")
		(comment 1 "Grand Teton / footprints 1616-1621 of 9728")
	)
	(layers
		(0 "F.Cu" signal "TOP")
		(4 "In1.Cu" signal "GND")
		(6 "In2.Cu" signal "VCC")
		(8 "In3.Cu" signal "VCC1")
		(10 "In4.Cu" signal "GND1")
		(12 "In5.Cu" signal "IN1")
		(14 "In6.Cu" signal "GND2")
		(16 "In7.Cu" signal "IN2")
		(18 "In8.Cu" signal "GND3")
		(20 "In9.Cu" signal "IN3")
		(22 "In10.Cu" signal "GND4")
		(24 "In11.Cu" signal "IN4")
		(26 "In12.Cu" signal "GND5")
		(28 "In13.Cu" signal "IN5")
		(30 "In14.Cu" signal "GND6")
		(32 "In15.Cu" signal "IN6")
		(34 "In16.Cu" signal "GND7")
		(2 "B.Cu" signal "BOTTOM")
		(9 "F.Adhes" user "F.Adhesive")
		(11 "B.Adhes" user "B.Adhesive")
		(13 "F.Paste" user "Package Geometry/Pastemask Top")
		(15 "B.Paste" user "Package Geometry/Pastemask Bottom")
		(5 "F.SilkS" user "Ref Des/Silkscreen Top")
		(7 "B.SilkS" user "Ref Des/Silkscreen Bottom")
		(1 "F.Mask" user "Board Geometry/Soldermask Top")
		(3 "B.Mask" user "Board Geometry/Soldermask Bottom")
		(17 "Dwgs.User" user "User.Drawings")
		(19 "Cmts.User" user "User.Comments")
		(21 "Eco1.User" user "User.Eco1")
		(23 "Eco2.User" user "User.Eco2")
		(25 "Edge.Cuts" user "Board Geometry/Outline")
		(27 "Margin" user)
		(31 "F.CrtYd" user "Package Geometry/Place Bound Top")
		(29 "B.CrtYd" user "Package Geometry/Place Bound Bottom")
		(35 "F.Fab" user "Ref Des/Assembly Top")
		(33 "B.Fab" user "Ref Des/Assembly Bottom")
	)
	(footprint ""
		(layer "F.Cu")
		(at 404.446232 -366.409478 180)
		(property "Reference" "R6679"
			(at 0 0 180)
			(layer "F.SilkS")
			(hide yes)
			(effects
				(font
					(size 1.27 1.27)
				)
			)
		)
		(property "Value" ""
			(at 0 0 180)
			(layer "F.Fab")
			(effects
				(font
					(size 1.27 1.27)
				)
			)
		)
		(duplicate_pad_numbers_are_jumpers no)
		(fp_line
			(start 0.7874 0.4064)
			(end -0.7874 0.4064)
			(stroke
				(width 0.1524)
				(type default)
			)
			(layer "F.SilkS")
		)
		(fp_line
			(start 0.7874 -0.4064)
			(end 0.7874 0.4064)
			(stroke
				(width 0.1524)
				(type default)
			)
			(layer "F.SilkS")
		)
		(fp_line
			(start -0.7874 0.4064)
			(end -0.7874 -0.4064)
			(stroke
				(width 0.1524)
				(type default)
			)
			(layer "F.SilkS")
		)
		(fp_line
			(start -0.7874 -0.4064)
			(end 0.7874 -0.4064)
			(stroke
				(width 0.1524)
				(type default)
			)
			(layer "F.SilkS")
		)
		(fp_line
			(start 0.67945 0.3048)
			(end 0.120396 0.3048)
			(stroke
				(width 0.1)
				(type default)
			)
			(layer "F.Fab")
		)
		(fp_line
			(start 0.67945 -0.3048)
			(end 0.67945 0.3048)
			(stroke
				(width 0.1)
				(type default)
			)
			(layer "F.Fab")
		)
		(fp_line
			(start 0.12065 -0.2794)
			(end 0.12065 -0.3048)
			(stroke
				(width 0.1)
				(type default)
			)
			(layer "F.Fab")
		)
		(fp_line
			(start 0.12065 -0.3048)
			(end 0.67945 -0.3048)
			(stroke
				(width 0.1)
				(type default)
			)
			(layer "F.Fab")
		)
		(fp_line
			(start 0.120396 0.3048)
			(end 0.120396 0.2794)
			(stroke
				(width 0.1)
				(type default)
			)
			(layer "F.Fab")
		)
		(fp_line
			(start 0.120396 0.2794)
			(end -0.12065 0.2794)
			(stroke
				(width 0.1)
				(type default)
			)
			(layer "F.Fab")
		)
		(fp_line
			(start -0.12065 0.3048)
			(end -0.67945 0.3048)
			(stroke
				(width 0.1)
				(type default)
			)
			(layer "F.Fab")
		)
		(fp_line
			(start -0.12065 0.2794)
			(end -0.12065 0.3048)
			(stroke
				(width 0.1)
				(type default)
			)
			(layer "F.Fab")
		)
		(fp_line
			(start -0.12065 -0.2794)
			(end 0.12065 -0.2794)
			(stroke
				(width 0.1)
				(type default)
			)
			(layer "F.Fab")
		)
		(fp_line
			(start -0.12065 -0.305054)
			(end -0.12065 -0.2794)
			(stroke
				(width 0.1)
				(type default)
			)
			(layer "F.Fab")
		)
		(fp_line
			(start -0.67945 0.3048)
			(end -0.67945 -0.305054)
			(stroke
				(width 0.1)
				(type default)
			)
			(layer "F.Fab")
		)
		(fp_line
			(start -0.67945 -0.305054)
			(end -0.12065 -0.305054)
			(stroke
				(width 0.1)
				(type default)
			)
			(layer "F.Fab")
		)
		(pad "1" smd circle
			(at -0.40005 0 180)
			(size 0 0)
			(layers "F.Cu" "F.Mask" "F.Paste")
			(net "GPU_3V3IO_RSVD1_ISO_R")
		)
		(pad "2" smd circle
			(at 0.40005 0 180)
			(size 0 0)
			(layers "F.Cu" "F.Mask" "F.Paste")
			(net "GPU_3V3IO_RSVD1_ISO")
		)
	)
	(footprint ""
		(layer "F.Cu")
		(at 392.938762 -22.867366 90)
		(property "Reference" "C3966"
			(at 0 0 90)
			(layer "F.SilkS")
			(hide yes)
			(effects
				(font
					(size 1.27 1.27)
				)
			)
		)
		(property "Value" ""
			(at 0 0 90)
			(layer "F.Fab")
			(effects
				(font
					(size 1.27 1.27)
				)
			)
		)
		(duplicate_pad_numbers_are_jumpers no)
		(fp_line
			(start 0.7874 -0.4064)
			(end 0.7874 0.4064)
			(stroke
				(width 0.1524)
				(type default)
			)
			(layer "F.SilkS")
		)
		(fp_line
			(start -0.7874 -0.4064)
			(end 0.7874 -0.4064)
			(stroke
				(width 0.1524)
				(type default)
			)
			(layer "F.SilkS")
		)
		(fp_line
			(start 0.7874 0.4064)
			(end -0.7874 0.4064)
			(stroke
				(width 0.1524)
				(type default)
			)
			(layer "F.SilkS")
		)
		(fp_line
			(start -0.7874 0.4064)
			(end -0.7874 -0.4064)
			(stroke
				(width 0.1524)
				(type default)
			)
			(layer "F.SilkS")
		)
		(fp_line
			(start -0.12065 -0.305054)
			(end -0.12065 -0.2794)
			(stroke
				(width 0.1)
				(type default)
			)
			(layer "F.Fab")
		)
		(fp_line
			(start -0.67945 -0.305054)
			(end -0.12065 -0.305054)
			(stroke
				(width 0.1)
				(type default)
			)
			(layer "F.Fab")
		)
		(fp_line
			(start 0.67945 -0.3048)
			(end 0.67945 0.3048)
			(stroke
				(width 0.1)
				(type default)
			)
			(layer "F.Fab")
		)
		(fp_line
			(start 0.12065 -0.3048)
			(end 0.67945 -0.3048)
			(stroke
				(width 0.1)
				(type default)
			)
			(layer "F.Fab")
		)
		(fp_line
			(start 0.12065 -0.2794)
			(end 0.12065 -0.3048)
			(stroke
				(width 0.1)
				(type default)
			)
			(layer "F.Fab")
		)
		(fp_line
			(start -0.12065 -0.2794)
			(end 0.12065 -0.2794)
			(stroke
				(width 0.1)
				(type default)
			)
			(layer "F.Fab")
		)
		(fp_line
			(start 0.120396 0.2794)
			(end -0.12065 0.2794)
			(stroke
				(width 0.1)
				(type default)
			)
			(layer "F.Fab")
		)
		(fp_line
			(start -0.12065 0.2794)
			(end -0.12065 0.3048)
			(stroke
				(width 0.1)
				(type default)
			)
			(layer "F.Fab")
		)
		(fp_line
			(start 0.67945 0.3048)
			(end 0.120396 0.3048)
			(stroke
				(width 0.1)
				(type default)
			)
			(layer "F.Fab")
		)
		(fp_line
			(start 0.120396 0.3048)
			(end 0.120396 0.2794)
			(stroke
				(width 0.1)
				(type default)
			)
			(layer "F.Fab")
		)
		(fp_line
			(start -0.12065 0.3048)
			(end -0.67945 0.3048)
			(stroke
				(width 0.1)
				(type default)
			)
			(layer "F.Fab")
		)
		(fp_line
			(start -0.67945 0.3048)
			(end -0.67945 -0.305054)
			(stroke
				(width 0.1)
				(type default)
			)
			(layer "F.Fab")
		)
		(pad "1" smd circle
			(at -0.40005 0 90)
			(size 0 0)
			(layers "F.Cu" "F.Mask" "F.Paste")
			(net "P12V_SSD13")
		)
		(pad "2" smd circle
			(at 0.40005 0 90)
			(size 0 0)
			(layers "F.Cu" "F.Mask" "F.Paste")
			(net "GND")
		)
	)
	(footprint ""
		(layer "F.Cu")
		(at 146.253454 -284.990032)
		(property "Reference" "L111"
			(at 0 0 0)
			(layer "F.SilkS")
			(hide yes)
			(effects
				(font
					(size 1.27 1.27)
				)
			)
		)
		(property "Value" ""
			(at 0 0 0)
			(layer "F.Fab")
			(effects
				(font
					(size 1.27 1.27)
				)
			)
		)
		(duplicate_pad_numbers_are_jumpers no)
		(fp_line
			(start -1.63576 -0.8128)
			(end -1.63576 0.8128)
			(stroke
				(width 0.1524)
				(type default)
			)
			(layer "F.SilkS")
		)
		(fp_line
			(start -1.63576 -0.8128)
			(end 1.63576 -0.8128)
			(stroke
				(width 0.1524)
				(type default)
			)
			(layer "F.SilkS")
		)
		(fp_line
			(start 1.63576 -0.8128)
			(end 1.63576 0.8128)
			(stroke
				(width 0.1524)
				(type default)
			)
			(layer "F.SilkS")
		)
		(fp_line
			(start 1.63576 0.8128)
			(end -1.63576 0.8128)
			(stroke
				(width 0.1524)
				(type default)
			)
			(layer "F.SilkS")
		)
		(fp_line
			(start -1.56083 -0.738632)
			(end -1.56083 0.7366)
			(stroke
				(width 0.1)
				(type default)
			)
			(layer "F.Fab")
		)
		(fp_line
			(start -1.56083 0.7366)
			(end -1.524 0.7366)
			(stroke
				(width 0.1)
				(type default)
			)
			(layer "F.Fab")
		)
		(fp_line
			(start -1.524 0.7366)
			(end 1.524 0.7366)
			(stroke
				(width 0.1)
				(type default)
			)
			(layer "F.Fab")
		)
		(fp_line
			(start 1.524 0.7366)
			(end 1.560576 0.7366)
			(stroke
				(width 0.1)
				(type default)
			)
			(layer "F.Fab")
		)
		(fp_line
			(start 1.560576 -0.738632)
			(end -1.56083 -0.738632)
			(stroke
				(width 0.1)
				(type default)
			)
			(layer "F.Fab")
		)
		(fp_line
			(start 1.560576 0.7366)
			(end 1.560576 -0.738632)
			(stroke
				(width 0.1)
				(type default)
			)
			(layer "F.Fab")
		)
		(pad "1" smd rect
			(at -0.94996 0 180)
			(size 1.1176 1.3716)
			(layers "F.Cu" "F.Mask" "F.Paste")
			(net "P1V8_PLL0_PEX1")
		)
		(pad "2" smd rect
			(at 0.94996 0 180)
			(size 1.1176 1.3716)
			(layers "F.Cu" "F.Mask" "F.Paste")
			(net "PCEPLL7_VDDA18_PEX1")
		)
	)
	(footprint ""
		(layer "F.Cu")
		(at 216.937844 -96.139 -90)
		(property "Reference" "R714"
			(at 0 0 270)
			(layer "F.SilkS")
			(hide yes)
			(effects
				(font
					(size 1.27 1.27)
				)
			)
		)
		(property "Value" ""
			(at 0 0 270)
			(layer "F.Fab")
			(effects
				(font
					(size 1.27 1.27)
				)
			)
		)
		(duplicate_pad_numbers_are_jumpers no)
		(fp_line
			(start -0.7874 0.4064)
			(end -0.7874 -0.4064)
			(stroke
				(width 0.1524)
				(type default)
			)
			(layer "F.SilkS")
		)
		(fp_line
			(start 0.7874 0.4064)
			(end -0.7874 0.4064)
			(stroke
				(width 0.1524)
				(type default)
			)
			(layer "F.SilkS")
		)
		(fp_line
			(start -0.7874 -0.4064)
			(end 0.7874 -0.4064)
			(stroke
				(width 0.1524)
				(type default)
			)
			(layer "F.SilkS")
		)
		(fp_line
			(start 0.7874 -0.4064)
			(end 0.7874 0.4064)
			(stroke
				(width 0.1524)
				(type default)
			)
			(layer "F.SilkS")
		)
		(fp_line
			(start -0.67945 0.3048)
			(end -0.67945 -0.305054)
			(stroke
				(width 0.1)
				(type default)
			)
			(layer "F.Fab")
		)
		(fp_line
			(start -0.12065 0.3048)
			(end -0.67945 0.3048)
			(stroke
				(width 0.1)
				(type default)
			)
			(layer "F.Fab")
		)
		(fp_line
			(start 0.120396 0.3048)
			(end 0.120396 0.2794)
			(stroke
				(width 0.1)
				(type default)
			)
			(layer "F.Fab")
		)
		(fp_line
			(start 0.67945 0.3048)
			(end 0.120396 0.3048)
			(stroke
				(width 0.1)
				(type default)
			)
			(layer "F.Fab")
		)
		(fp_line
			(start -0.12065 0.2794)
			(end -0.12065 0.3048)
			(stroke
				(width 0.1)
				(type default)
			)
			(layer "F.Fab")
		)
		(fp_line
			(start 0.120396 0.2794)
			(end -0.12065 0.2794)
			(stroke
				(width 0.1)
				(type default)
			)
			(layer "F.Fab")
		)
		(fp_line
			(start -0.12065 -0.2794)
			(end 0.12065 -0.2794)
			(stroke
				(width 0.1)
				(type default)
			)
			(layer "F.Fab")
		)
		(fp_line
			(start 0.12065 -0.2794)
			(end 0.12065 -0.3048)
			(stroke
				(width 0.1)
				(type default)
			)
			(layer "F.Fab")
		)
		(fp_line
			(start 0.12065 -0.3048)
			(end 0.67945 -0.3048)
			(stroke
				(width 0.1)
				(type default)
			)
			(layer "F.Fab")
		)
		(fp_line
			(start 0.67945 -0.3048)
			(end 0.67945 0.3048)
			(stroke
				(width 0.1)
				(type default)
			)
			(layer "F.Fab")
		)
		(fp_line
			(start -0.67945 -0.305054)
			(end -0.12065 -0.305054)
			(stroke
				(width 0.1)
				(type default)
			)
			(layer "F.Fab")
		)
		(fp_line
			(start -0.12065 -0.305054)
			(end -0.12065 -0.2794)
			(stroke
				(width 0.1)
				(type default)
			)
			(layer "F.Fab")
		)
		(pad "1" smd circle
			(at -0.40005 0 270)
			(size 0 0)
			(layers "F.Cu" "F.Mask" "F.Paste")
			(net "NIC3_ADC_A1")
		)
		(pad "2" smd circle
			(at 0.40005 0 270)
			(size 0 0)
			(layers "F.Cu" "F.Mask" "F.Paste")
			(net "P3V3_AUX")
		)
	)
	(footprint ""
		(layer "F.Cu")
		(at 330.687426 -25.342342 -90)
		(property "Reference" "R443"
			(at 0 0 270)
			(layer "F.SilkS")
			(hide yes)
			(effects
				(font
					(size 1.27 1.27)
				)
			)
		)
		(property "Value" ""
			(at 0 0 270)
			(layer "F.Fab")
			(effects
				(font
					(size 1.27 1.27)
				)
			)
		)
		(duplicate_pad_numbers_are_jumpers no)
		(fp_line
			(start -0.7874 0.4064)
			(end -0.7874 -0.4064)
			(stroke
				(width 0.1524)
				(type default)
			)
			(layer "F.SilkS")
		)
		(fp_line
			(start 0.7874 0.4064)
			(end -0.7874 0.4064)
			(stroke
				(width 0.1524)
				(type default)
			)
			(layer "F.SilkS")
		)
		(fp_line
			(start -0.7874 -0.4064)
			(end 0.7874 -0.4064)
			(stroke
				(width 0.1524)
				(type default)
			)
			(layer "F.SilkS")
		)
		(fp_line
			(start 0.7874 -0.4064)
			(end 0.7874 0.4064)
			(stroke
				(width 0.1524)
				(type default)
			)
			(layer "F.SilkS")
		)
		(fp_line
			(start -0.67945 0.3048)
			(end -0.67945 -0.305054)
			(stroke
				(width 0.1)
				(type default)
			)
			(layer "F.Fab")
		)
		(fp_line
			(start -0.12065 0.3048)
			(end -0.67945 0.3048)
			(stroke
				(width 0.1)
				(type default)
			)
			(layer "F.Fab")
		)
		(fp_line
			(start 0.120396 0.3048)
			(end 0.120396 0.2794)
			(stroke
				(width 0.1)
				(type default)
			)
			(layer "F.Fab")
		)
		(fp_line
			(start 0.67945 0.3048)
			(end 0.120396 0.3048)
			(stroke
				(width 0.1)
				(type default)
			)
			(layer "F.Fab")
		)
		(fp_line
			(start -0.12065 0.2794)
			(end -0.12065 0.3048)
			(stroke
				(width 0.1)
				(type default)
			)
			(layer "F.Fab")
		)
		(fp_line
			(start 0.120396 0.2794)
			(end -0.12065 0.2794)
			(stroke
				(width 0.1)
				(type default)
			)
			(layer "F.Fab")
		)
		(fp_line
			(start -0.12065 -0.2794)
			(end 0.12065 -0.2794)
			(stroke
				(width 0.1)
				(type default)
			)
			(layer "F.Fab")
		)
		(fp_line
			(start 0.12065 -0.2794)
			(end 0.12065 -0.3048)
			(stroke
				(width 0.1)
				(type default)
			)
			(layer "F.Fab")
		)
		(fp_line
			(start 0.12065 -0.3048)
			(end 0.67945 -0.3048)
			(stroke
				(width 0.1)
				(type default)
			)
			(layer "F.Fab")
		)
		(fp_line
			(start 0.67945 -0.3048)
			(end 0.67945 0.3048)
			(stroke
				(width 0.1)
				(type default)
			)
			(layer "F.Fab")
		)
		(fp_line
			(start -0.67945 -0.305054)
			(end -0.12065 -0.305054)
			(stroke
				(width 0.1)
				(type default)
			)
			(layer "F.Fab")
		)
		(fp_line
			(start -0.12065 -0.305054)
			(end -0.12065 -0.2794)
			(stroke
				(width 0.1)
				(type default)
			)
			(layer "F.Fab")
		)
		(pad "1" smd circle
			(at -0.40005 0 270)
			(size 0 0)
			(layers "F.Cu" "F.Mask" "F.Paste")
			(net "GND")
		)
		(pad "2" smd circle
			(at 0.40005 0 270)
			(size 0 0)
			(layers "F.Cu" "F.Mask" "F.Paste")
			(net "DUALPORT_N_SSD11")
		)
	)
	(footprint ""
		(layer "F.Cu")
		(at 381.127 -212.344)
		(property "Reference" "R4637"
			(at 0 0 0)
			(layer "F.SilkS")
			(hide yes)
			(effects
				(font
					(size 1.27 1.27)
				)
			)
		)
		(property "Value" ""
			(at 0 0 0)
			(layer "F.Fab")
			(effects
				(font
					(size 1.27 1.27)
				)
			)
		)
		(duplicate_pad_numbers_are_jumpers no)
		(fp_line
			(start -0.7874 -0.4064)
			(end 0.7874 -0.4064)
			(stroke
				(width 0.1524)
				(type default)
			)
			(layer "F.SilkS")
		)
		(fp_line
			(start -0.7874 0.4064)
			(end -0.7874 -0.4064)
			(stroke
				(width 0.1524)
				(type default)
			)
			(layer "F.SilkS")
		)
		(fp_line
			(start 0.7874 -0.4064)
			(end 0.7874 0.4064)
			(stroke
				(width 0.1524)
				(type default)
			)
			(layer "F.SilkS")
		)
		(fp_line
			(start 0.7874 0.4064)
			(end -0.7874 0.4064)
			(stroke
				(width 0.1524)
				(type default)
			)
			(layer "F.SilkS")
		)
		(fp_line
			(start -0.67945 -0.305054)
			(end -0.12065 -0.305054)
			(stroke
				(width 0.1)
				(type default)
			)
			(layer "F.Fab")
		)
		(fp_line
			(start -0.67945 0.3048)
			(end -0.67945 -0.305054)
			(stroke
				(width 0.1)
				(type default)
			)
			(layer "F.Fab")
		)
		(fp_line
			(start -0.12065 -0.305054)
			(end -0.12065 -0.2794)
			(stroke
				(width 0.1)
				(type default)
			)
			(layer "F.Fab")
		)
		(fp_line
			(start -0.12065 -0.2794)
			(end 0.12065 -0.2794)
			(stroke
				(width 0.1)
				(type default)
			)
			(layer "F.Fab")
		)
		(fp_line
			(start -0.12065 0.2794)
			(end -0.12065 0.3048)
			(stroke
				(width 0.1)
				(type default)
			)
			(layer "F.Fab")
		)
		(fp_line
			(start -0.12065 0.3048)
			(end -0.67945 0.3048)
			(stroke
				(width 0.1)
				(type default)
			)
			(layer "F.Fab")
		)
		(fp_line
			(start 0.120396 0.2794)
			(end -0.12065 0.2794)
			(stroke
				(width 0.1)
				(type default)
			)
			(layer "F.Fab")
		)
		(fp_line
			(start 0.120396 0.3048)
			(end 0.120396 0.2794)
			(stroke
				(width 0.1)
				(type default)
			)
			(layer "F.Fab")
		)
		(fp_line
			(start 0.12065 -0.3048)
			(end 0.67945 -0.3048)
			(stroke
				(width 0.1)
				(type default)
			)
			(layer "F.Fab")
		)
		(fp_line
			(start 0.12065 -0.2794)
			(end 0.12065 -0.3048)
			(stroke
				(width 0.1)
				(type default)
			)
			(layer "F.Fab")
		)
		(fp_line
			(start 0.67945 -0.3048)
			(end 0.67945 0.3048)
			(stroke
				(width 0.1)
				(type default)
			)
			(layer "F.Fab")
		)
		(fp_line
			(start 0.67945 0.3048)
			(end 0.120396 0.3048)
			(stroke
				(width 0.1)
				(type default)
			)
			(layer "F.Fab")
		)
		(pad "1" smd circle
			(at -0.40005 0)
			(size 0 0)
			(layers "F.Cu" "F.Mask" "F.Paste")
			(net "GND")
		)
		(pad "2" smd circle
			(at 0.40005 0)
			(size 0 0)
			(layers "F.Cu" "F.Mask" "F.Paste")
			(net "PCA9555_0_PEX0_A0")
		)
	)
)
